G04 ================== begin FILE IDENTIFICATION RECORD ==================*
G04 Layout Name:  15750-1.brd*
G04 Film Name:    P_OUTLINE*
G04 File Format:  Gerber RS274X*
G04 File Origin:  Cadence Allegro 16.5-S056*
G04 Origin Date:  Fri Dec 30 13:21:25 2016*
G04 *
G04 Layer:  BOARD GEOMETRY/PANEL_OUTLINE*
G04 *
G04 Offset:    (0.00 0.00)*
G04 Mirror:    No*
G04 Mode:      Positive*
G04 Rotation:  0*
G04 FullContactRelief:  No*
G04 UndefLineWidth:     6.00*
G04 ================== end FILE IDENTIFICATION RECORD ====================*
%FSLAX35Y35*MOIN*%
%IR0*IPPOS*OFA0.00000B0.00000*MIA0B0*SFA1.00000B1.00000*%
%ADD10C,.006*%
G75*
%LPD*%
G75*
G54D10*
G01X-1Y-113228D02*
Y-117165D01*
G03X7873Y-125039I7874J0D01*
G01X714566D01*
G03X722440Y-117165I0J7874D01*
G01Y-113228D01*
G01X1968Y40473D02*
X9842D01*
G02X11811Y38504I0J-1969D01*
G01Y-16772D01*
G02X9842Y-18740I-1969J1D01*
G01X1968D01*
G03X0Y-20709I0J-1968D01*
G01Y-97480D01*
G03X7874Y-105354I7874J0D01*
G01X341535D01*
G03X349409Y-97480I0J7874D01*
G01Y-15748D01*
G03X341535Y-7874I-7874J0D01*
G01X141338D01*
G02X133464Y0I0J7874D01*
G01Y250197D01*
G03X125590Y258071I-7874J0D01*
G01X1968D01*
G03X0Y256102I0J-1968D01*
G01Y236673D01*
G03X1968Y234705I1968J0D01*
G01X28346D01*
G02X30315Y232736I0J-1969D01*
G01Y216004D01*
G02X28346Y214036I-1968J0D01*
G01X23228D01*
G03X21259Y212067I0J-1969D01*
G01Y86752D01*
G03X23228Y84784I1969J1D01*
G01X28346D01*
G02X30315Y82815I0J-1969D01*
G01Y66083D01*
G02X28346Y64114I-1969J0D01*
G01X1968D01*
G03X0Y62146I0J-1968D01*
G01Y42441D01*
G03X1968Y40473I1968J0D01*
G01X-1Y-113228D02*
X13591D01*
G01X347441Y217598D02*
X339567D01*
G02X337598Y219567I0J1969D01*
G01Y274843D01*
G02X339567Y276811I1969J-1D01*
G01X347441D01*
G03X349409Y278780I0J1968D01*
G01Y355551D01*
G03X341535Y363425I-7874J0D01*
G01X7874D01*
G03X0Y355551I0J-7874D01*
G01Y273819D01*
G03X7874Y265945I7874J0D01*
G01X208071D01*
G02X215945Y258071I0J-7874D01*
G01Y7874D01*
G03X223819Y0I7874J0D01*
G01X347441D01*
G03X349409Y1969I0J1968D01*
G01Y21398D01*
G03X347441Y23366I-1968J0D01*
G01X321063D01*
G02X319094Y25335I0J1969D01*
G01Y42067D01*
G02X321063Y44035I1969J-1D01*
G01X326181D01*
G03X328150Y46004I0J1969D01*
G01Y171319D01*
G03X326181Y173287I-1968J0D01*
G01X321063D01*
G02X319094Y175256I0J1969D01*
G01Y191988D01*
G02X321063Y193957I1969J0D01*
G01X347441D01*
G03X349409Y195925I0J1968D01*
G01Y215630D01*
G03X347441Y217598I-1968J0D01*
G01X245745Y383110D02*
X7874D01*
G03X0Y375236I0J-7874D01*
G01Y371299D01*
G01D02*
X13591D01*
G01Y-113228D02*
G03Y-105354I0J3937D01*
G01Y258071D02*
G03Y265945I0J3937D01*
G01Y363425D02*
G03Y371299I0J3937D01*
G01X38787Y-113228D02*
X237000D01*
G01X38787Y-105354D02*
G03Y-113228I1J-3937D01*
G01Y265945D02*
G03Y258071I1J-3937D01*
G01X237000Y371299D02*
X38787D01*
G01D02*
G03Y363425I1J-3937D01*
G01X141338Y116437D02*
G03X133464I-3937J0D01*
G01Y141634D02*
G03X141338I3937J0D01*
G01Y0D02*
Y116437D01*
G01X162106Y0D02*
X141337D01*
G01X141338Y141634D02*
Y258071D01*
G01D02*
X162106D01*
G01Y-7874D02*
G03Y0I0J3937D01*
G01X179626Y62719D02*
G03X171044I-4291J0D01*
G03X179626I4291J0D01*
G01Y189063D02*
G03X171044Y189062I-4291J0D01*
G03X179626Y189063I4291J1D01*
G01X162106Y258071D02*
G03Y265945I0J3937D01*
G01X187302Y0D02*
G03Y-7874I1J-3937D01*
G01X208071Y0D02*
X187302D01*
G01Y265945D02*
G03Y258071I1J-3937D01*
G01D02*
X208071D01*
G01X207913Y0D02*
X208071D01*
G01Y116437D02*
Y0D01*
G01X215945Y116437D02*
G03X208071I-3937J0D01*
G01Y141634D02*
G03X215945I3937J0D01*
G01X208071Y258071D02*
Y141634D01*
G01X237000Y-113228D02*
G03Y-105354I0J3937D01*
G01Y363425D02*
G03Y371299I0J3937D01*
G01X245745Y383110D02*
G03X253619I3937J0D01*
G01X722440Y371299D02*
Y375236D01*
G03X714566Y383110I-7874J0D01*
G01X253619D01*
G01X262196Y-113228D02*
X460244D01*
G01X262196Y-105354D02*
G03Y-113228I0J-3937D01*
G01Y371299D02*
X460244D01*
G01X262196D02*
G03Y363425I0J-3937D01*
G01X310621Y-7874D02*
G03Y0I0J3937D01*
G01X335817D02*
G03Y-7874I1J-3937D01*
G01X353346Y-47481D02*
G03X349409Y-51418I0J-3937D01*
G01Y-20709D02*
G03X353346Y-24646I3937J0D01*
G01Y282717D02*
G03X349409Y278780I0J-3937D01*
G01Y309489D02*
G03X353346Y305552I3937J0D01*
G01Y-47481D02*
X369094D01*
G01X373031Y-51418D02*
G03X369094Y-47481I-3937J0D01*
G01X353346Y-24646D02*
X369094D01*
G01D02*
G03X373031Y-20709I0J3937D01*
G01X353346Y282717D02*
X369094D01*
G01X373031Y278780D02*
G03X369094Y282717I-3937J0D01*
G01X353346Y305552D02*
X369094D01*
G01D02*
G03X373031Y309489I0J3937D01*
G01X374999Y40473D02*
X382873D01*
G02X384842Y38504I0J-1969D01*
G01Y-16772D01*
G02X382873Y-18740I-1969J1D01*
G01X374999D01*
G03X373031Y-20709I0J-1968D01*
G01Y-97480D01*
G03X380905Y-105354I7874J0D01*
G01X714566D01*
G03X722440Y-97480I0J7874D01*
G01Y-15748D01*
G03X714566Y-7874I-7874J0D01*
G01X514369D01*
G02X506495Y0I0J7874D01*
G01Y250197D01*
G03X498621Y258071I-7874J0D01*
G01X374999D01*
G03X373031Y256102I0J-1968D01*
G01Y236673D01*
G03X374999Y234705I1968J0D01*
G01X401377D01*
G02X403346Y232736I0J-1969D01*
G01Y216004D01*
G02X401377Y214036I-1968J0D01*
G01X396259D01*
G03X394290Y212067I0J-1969D01*
G01Y86752D01*
G03X396259Y84784I1969J1D01*
G01X401377D01*
G02X403346Y82815I0J-1969D01*
G01Y66083D01*
G02X401377Y64114I-1969J0D01*
G01X374999D01*
G03X373031Y62146I0J-1968D01*
G01Y42441D01*
G03X374999Y40473I1968J0D01*
G01X720472Y217598D02*
X712598D01*
G02X710629Y219567I0J1969D01*
G01Y274843D01*
G02X712598Y276811I1969J-1D01*
G01X720472D01*
G03X722440Y278780I0J1968D01*
G01Y355551D01*
G03X714566Y363425I-7874J0D01*
G01X380905D01*
G03X373031Y355551I0J-7874D01*
G01Y273819D01*
G03X380905Y265945I7874J0D01*
G01X581102D01*
G02X588976Y258071I0J-7874D01*
G01Y7874D01*
G03X596850Y0I7874J0D01*
G01X720472D01*
G03X722440Y1969I0J1968D01*
G01Y21398D01*
G03X720472Y23366I-1968J0D01*
G01X694094D01*
G02X692125Y25335I0J1969D01*
G01Y42067D01*
G02X694094Y44035I1969J-1D01*
G01X699212D01*
G03X701181Y46004I0J1969D01*
G01Y171319D01*
G03X699212Y173287I-1969J-1D01*
G01X694094D01*
G02X692125Y175256I0J1969D01*
G01Y191988D01*
G02X694094Y193957I1969J0D01*
G01X720472D01*
G03X722440Y195925I0J1968D01*
G01Y215630D01*
G03X720472Y217598I-1968J0D01*
G01X386622Y258071D02*
G03Y265945I0J3937D01*
G01X411819D02*
G03Y258071I0J-3937D01*
G01X460244Y-113228D02*
G03Y-105354I0J3937D01*
G01Y363425D02*
G03Y371299I0J3937D01*
G01X485441Y-105354D02*
G03Y-113228I0J-3937D01*
G01Y371299D02*
G03Y363425I0J-3937D01*
G01Y-113228D02*
X683652D01*
G01X485441Y371299D02*
X683652D01*
G01X514369Y0D02*
Y116437D01*
G01X535137Y0D02*
X514369D01*
G01Y116437D02*
G03X506494I-3937J0D01*
G01Y141634D02*
G03X514369I3937J0D01*
G01D02*
Y258071D01*
G01D02*
X535137D01*
G01Y-7874D02*
G03Y0I0J3937D01*
G01X551396Y69008D02*
G03X542813I-4291J0D01*
G03X551396I4291J0D01*
G01Y195351D02*
G03X542813Y195352I-4292J0D01*
G03X551396Y195351I4291J-1D01*
G01X535137Y258071D02*
G03Y265945I0J3937D01*
G01X560333Y0D02*
G03Y-7874I1J-3937D01*
G01X581102Y0D02*
X560333D01*
G01Y265945D02*
G03Y258071I1J-3937D01*
G01D02*
X581102D01*
G01Y116437D02*
Y0D01*
G01X588976Y116437D02*
G03X581102I-3937J0D01*
G01Y141634D02*
G03X588976I3937J0D01*
G01X581102Y258071D02*
Y141634D01*
G01X683652Y-113228D02*
G03Y-105354I0J3937D01*
G01Y-7874D02*
G03Y0I0J3937D01*
G01Y363425D02*
G03Y371299I0J3937D01*
G01X708848Y-113228D02*
X722440D01*
G01X708848Y-105354D02*
G03Y-113228I1J-3937D01*
G01Y0D02*
G03Y-7874I1J-3937D01*
G01Y371299D02*
X722440D01*
G01X708848D02*
G03Y363425I1J-3937D01*
M02*
